# S9S_MB_2U (Grand Teton) — schematic netlist excerpt (pin names and nets, part order shuffled) for the footprints in the layout excerpt that follows; sources: Cadence DE-HDL packaged netlist, KiCad conversion of 03242023_DA0F0TMBIJ0_F0T_Motherboard_J_brd_V01_OCP.brd

R593  Q_RES  0 5% CHIP  pkg 0402LF  page 241 : A = I3C_SPD_DDRABCD_CPU0_BMC_R_SCL ; B = I3C_SPD_DDRABCD_CPU0_BMC_SCL
R289  Q_RES  240 1% EMPTY  pkg 0402LF  page 119 : A = PD_CPU1_TXT_PLTEN ; B = GND

(kicad_pcb
	(version 20260206)
	(generator "pcbnew")
	(generator_version "10.0")
	(general
		(thickness 1.6)
		(legacy_teardrops no)
	)
	(paper "A4")
	(title_block
		(title "03242023_DA0F0TMBIJ0_F0T_Motherboard_J_brd_V01_OCP.brd")
		(comment 1 "Grand Teton / footprints 6090-6091 of 6105")
	)
	(layers
		(0 "F.Cu" signal "TOP")
		(4 "In1.Cu" signal "GND")
		(6 "In2.Cu" signal "IN1")
		(8 "In3.Cu" signal "GND1")
		(10 "In4.Cu" signal "IN2")
		(12 "In5.Cu" signal "GND2")
		(14 "In6.Cu" signal "IN3")
		(16 "In7.Cu" signal "GND3")
		(18 "In8.Cu" signal "VCC")
		(20 "In9.Cu" signal "VCC1")
		(22 "In10.Cu" signal "GND4")
		(24 "In11.Cu" signal "IN4")
		(26 "In12.Cu" signal "GND5")
		(28 "In13.Cu" signal "IN5")
		(30 "In14.Cu" signal "GND6")
		(32 "In15.Cu" signal "IN6")
		(34 "In16.Cu" signal "GND7")
		(2 "B.Cu" signal "BOTTOM")
		(9 "F.Adhes" user "F.Adhesive")
		(11 "B.Adhes" user "B.Adhesive")
		(13 "F.Paste" user "Package Geometry/Pastemask Top")
		(15 "B.Paste" user "Package Geometry/Pastemask Bottom")
		(5 "F.SilkS" user "Ref Des/Silkscreen Top")
		(7 "B.SilkS" user "Ref Des/Silkscreen Bottom")
		(1 "F.Mask" user "Board Geometry/Soldermask Top")
		(3 "B.Mask" user "Board Geometry/Soldermask Bottom")
		(17 "Dwgs.User" user "User.Drawings")
		(19 "Cmts.User" user "User.Comments")
		(21 "Eco1.User" user "User.Eco1")
		(23 "Eco2.User" user "User.Eco2")
		(25 "Edge.Cuts" user "Board Geometry/Outline")
		(27 "Margin" user)
		(31 "F.CrtYd" user "Package Geometry/Place Bound Top")
		(29 "B.CrtYd" user "Package Geometry/Place Bound Bottom")
		(35 "F.Fab" user "Ref Des/Assembly Top")
		(33 "B.Fab" user "Ref Des/Assembly Bottom")
	)
	(footprint ""
		(layer "B.Cu")
		(at 149.278848 -188.21019)
		(property "Reference" "R289"
			(at 0 0 0)
			(layer "B.SilkS")
			(hide yes)
			(effects
				(font
					(size 1.27 1.27)
				)
				(justify mirror)
			)
		)
		(property "Value" ""
			(at 0 0 0)
			(layer "B.Fab")
			(effects
				(font
					(size 1.27 1.27)
				)
				(justify mirror)
			)
		)
		(duplicate_pad_numbers_are_jumpers no)
		(fp_line
			(start -0.7874 -0.4064)
			(end -0.7874 0.4064)
			(stroke
				(width 0.1524)
				(type default)
			)
			(layer "B.SilkS")
		)
		(fp_line
			(start -0.7874 0.4064)
			(end 0.7874 0.4064)
			(stroke
				(width 0.1524)
				(type default)
			)
			(layer "B.SilkS")
		)
		(fp_line
			(start 0.7874 -0.4064)
			(end -0.7874 -0.4064)
			(stroke
				(width 0.1524)
				(type default)
			)
			(layer "B.SilkS")
		)
		(fp_line
			(start 0.7874 0.4064)
			(end 0.7874 -0.4064)
			(stroke
				(width 0.1524)
				(type default)
			)
			(layer "B.SilkS")
		)
		(fp_line
			(start -0.67945 -0.3048)
			(end -0.67945 0.3048)
			(stroke
				(width 0.1)
				(type default)
			)
			(layer "B.Fab")
		)
		(fp_line
			(start -0.67945 0.3048)
			(end -0.120396 0.3048)
			(stroke
				(width 0.1)
				(type default)
			)
			(layer "B.Fab")
		)
		(fp_line
			(start -0.12065 -0.3048)
			(end -0.67945 -0.3048)
			(stroke
				(width 0.1)
				(type default)
			)
			(layer "B.Fab")
		)
		(fp_line
			(start -0.12065 -0.2794)
			(end -0.12065 -0.3048)
			(stroke
				(width 0.1)
				(type default)
			)
			(layer "B.Fab")
		)
		(fp_line
			(start -0.120396 0.2794)
			(end 0.12065 0.2794)
			(stroke
				(width 0.1)
				(type default)
			)
			(layer "B.Fab")
		)
		(fp_line
			(start -0.120396 0.3048)
			(end -0.120396 0.2794)
			(stroke
				(width 0.1)
				(type default)
			)
			(layer "B.Fab")
		)
		(fp_line
			(start 0.12065 -0.305054)
			(end 0.12065 -0.2794)
			(stroke
				(width 0.1)
				(type default)
			)
			(layer "B.Fab")
		)
		(fp_line
			(start 0.12065 -0.2794)
			(end -0.12065 -0.2794)
			(stroke
				(width 0.1)
				(type default)
			)
			(layer "B.Fab")
		)
		(fp_line
			(start 0.12065 0.2794)
			(end 0.12065 0.3048)
			(stroke
				(width 0.1)
				(type default)
			)
			(layer "B.Fab")
		)
		(fp_line
			(start 0.12065 0.3048)
			(end 0.67945 0.3048)
			(stroke
				(width 0.1)
				(type default)
			)
			(layer "B.Fab")
		)
		(fp_line
			(start 0.67945 -0.305054)
			(end 0.12065 -0.305054)
			(stroke
				(width 0.1)
				(type default)
			)
			(layer "B.Fab")
		)
		(fp_line
			(start 0.67945 0.3048)
			(end 0.67945 -0.305054)
			(stroke
				(width 0.1)
				(type default)
			)
			(layer "B.Fab")
		)
		(pad "1" smd circle
			(at 0.40005 0 180)
			(size 0 0)
			(layers "B.Cu" "B.Mask" "B.Paste")
			(net "PD_CPU1_TXT_PLTEN")
		)
		(pad "2" smd circle
			(at -0.40005 0 180)
			(size 0 0)
			(layers "B.Cu" "B.Mask" "B.Paste")
			(net "GND")
		)
	)
	(footprint ""
		(layer "B.Cu")
		(at 190.367158 -13.60043 -90)
		(property "Reference" "R593"
			(at 0 0 90)
			(layer "B.SilkS")
			(hide yes)
			(effects
				(font
					(size 1.27 1.27)
				)
				(justify mirror)
			)
		)
		(property "Value" ""
			(at 0 0 90)
			(layer "B.Fab")
			(effects
				(font
					(size 1.27 1.27)
				)
				(justify mirror)
			)
		)
		(duplicate_pad_numbers_are_jumpers no)
		(fp_line
			(start -0.7874 0.4064)
			(end 0.7874 0.4064)
			(stroke
				(width 0.1524)
				(type default)
			)
			(layer "B.SilkS")
		)
		(fp_line
			(start 0.7874 0.4064)
			(end 0.7874 -0.4064)
			(stroke
				(width 0.1524)
				(type default)
			)
			(layer "B.SilkS")
		)
		(fp_line
			(start -0.7874 -0.4064)
			(end -0.7874 0.4064)
			(stroke
				(width 0.1524)
				(type default)
			)
			(layer "B.SilkS")
		)
		(fp_line
			(start 0.7874 -0.4064)
			(end -0.7874 -0.4064)
			(stroke
				(width 0.1524)
				(type default)
			)
			(layer "B.SilkS")
		)
		(fp_line
			(start -0.67945 0.3048)
			(end -0.120396 0.3048)
			(stroke
				(width 0.1)
				(type default)
			)
			(layer "B.Fab")
		)
		(fp_line
			(start -0.120396 0.3048)
			(end -0.120396 0.2794)
			(stroke
				(width 0.1)
				(type default)
			)
			(layer "B.Fab")
		)
		(fp_line
			(start 0.12065 0.3048)
			(end 0.67945 0.3048)
			(stroke
				(width 0.1)
				(type default)
			)
			(layer "B.Fab")
		)
		(fp_line
			(start 0.67945 0.3048)
			(end 0.67945 -0.305054)
			(stroke
				(width 0.1)
				(type default)
			)
			(layer "B.Fab")
		)
		(fp_line
			(start -0.120396 0.2794)
			(end 0.12065 0.2794)
			(stroke
				(width 0.1)
				(type default)
			)
			(layer "B.Fab")
		)
		(fp_line
			(start 0.12065 0.2794)
			(end 0.12065 0.3048)
			(stroke
				(width 0.1)
				(type default)
			)
			(layer "B.Fab")
		)
		(fp_line
			(start -0.12065 -0.2794)
			(end -0.12065 -0.3048)
			(stroke
				(width 0.1)
				(type default)
			)
			(layer "B.Fab")
		)
		(fp_line
			(start 0.12065 -0.2794)
			(end -0.12065 -0.2794)
			(stroke
				(width 0.1)
				(type default)
			)
			(layer "B.Fab")
		)
		(fp_line
			(start -0.67945 -0.3048)
			(end -0.67945 0.3048)
			(stroke
				(width 0.1)
				(type default)
			)
			(layer "B.Fab")
		)
		(fp_line
			(start -0.12065 -0.3048)
			(end -0.67945 -0.3048)
			(stroke
				(width 0.1)
				(type default)
			)
			(layer "B.Fab")
		)
		(fp_line
			(start 0.12065 -0.305054)
			(end 0.12065 -0.2794)
			(stroke
				(width 0.1)
				(type default)
			)
			(layer "B.Fab")
		)
		(fp_line
			(start 0.67945 -0.305054)
			(end 0.12065 -0.305054)
			(stroke
				(width 0.1)
				(type default)
			)
			(layer "B.Fab")
		)
		(pad "1" smd circle
			(at 0.40005 0 90)
			(size 0 0)
			(layers "B.Cu" "B.Mask" "B.Paste")
			(net "I3C_SPD_DDRABCD_CPU0_BMC_R_SCL")
		)
		(pad "2" smd circle
			(at -0.40005 0 90)
			(size 0 0)
			(layers "B.Cu" "B.Mask" "B.Paste")
			(net "I3C_SPD_DDRABCD_CPU0_BMC_SCL")
		)
	)
)
